# S9S_MB_2U (Grand Teton) — schematic netlist excerpt (pin names and nets, part order shuffled) for the footprints in the layout excerpt that follows; sources: Cadence DE-HDL packaged netlist, KiCad conversion of 03242023_DA0F0TMBIJ0_F0T_Motherboard_J_brd_V01_OCP.brd

R3978  Q_RES  100K 1% EMPTY  pkg 0402LF  page 192 : A = P3V3_AUX ; B = HP_LVC3_E1S_0_HSC_PWRGD
PC2149  Q_CAP  0.01UF 50V 10% EMPTY  pkg C0402  page 162 : A = P3V3_OCP_V3_2_R ; B = P3V3_OCP_GATE_2

(kicad_pcb
	(version 20260206)
	(generator "pcbnew")
	(generator_version "10.0")
	(general
		(thickness 1.6)
		(legacy_teardrops no)
	)
	(paper "A4")
	(title_block
		(title "03242023_DA0F0TMBIJ0_F0T_Motherboard_J_brd_V01_OCP.brd")
		(comment 1 "Grand Teton / footprints 1393-1394 of 6105")
	)
	(layers
		(0 "F.Cu" signal "TOP")
		(4 "In1.Cu" signal "GND")
		(6 "In2.Cu" signal "IN1")
		(8 "In3.Cu" signal "GND1")
		(10 "In4.Cu" signal "IN2")
		(12 "In5.Cu" signal "GND2")
		(14 "In6.Cu" signal "IN3")
		(16 "In7.Cu" signal "GND3")
		(18 "In8.Cu" signal "VCC")
		(20 "In9.Cu" signal "VCC1")
		(22 "In10.Cu" signal "GND4")
		(24 "In11.Cu" signal "IN4")
		(26 "In12.Cu" signal "GND5")
		(28 "In13.Cu" signal "IN5")
		(30 "In14.Cu" signal "GND6")
		(32 "In15.Cu" signal "IN6")
		(34 "In16.Cu" signal "GND7")
		(2 "B.Cu" signal "BOTTOM")
		(9 "F.Adhes" user "F.Adhesive")
		(11 "B.Adhes" user "B.Adhesive")
		(13 "F.Paste" user "Package Geometry/Pastemask Top")
		(15 "B.Paste" user "Package Geometry/Pastemask Bottom")
		(5 "F.SilkS" user "Ref Des/Silkscreen Top")
		(7 "B.SilkS" user "Ref Des/Silkscreen Bottom")
		(1 "F.Mask" user "Board Geometry/Soldermask Top")
		(3 "B.Mask" user "Board Geometry/Soldermask Bottom")
		(17 "Dwgs.User" user "User.Drawings")
		(19 "Cmts.User" user "User.Comments")
		(21 "Eco1.User" user "User.Eco1")
		(23 "Eco2.User" user "User.Eco2")
		(25 "Edge.Cuts" user "Board Geometry/Outline")
		(27 "Margin" user)
		(31 "F.CrtYd" user "Package Geometry/Place Bound Top")
		(29 "B.CrtYd" user "Package Geometry/Place Bound Bottom")
		(35 "F.Fab" user "Ref Des/Assembly Top")
		(33 "B.Fab" user "Ref Des/Assembly Bottom")
	)
	(footprint ""
		(layer "F.Cu")
		(at 252.222 -37.667946 180)
		(property "Reference" "R3978"
			(at 0 0 180)
			(layer "F.SilkS")
			(hide yes)
			(effects
				(font
					(size 1.27 1.27)
				)
			)
		)
		(property "Value" ""
			(at 0 0 180)
			(layer "F.Fab")
			(effects
				(font
					(size 1.27 1.27)
				)
			)
		)
		(duplicate_pad_numbers_are_jumpers no)
		(fp_line
			(start 0.7874 0.4064)
			(end -0.7874 0.4064)
			(stroke
				(width 0.1524)
				(type default)
			)
			(layer "F.SilkS")
		)
		(fp_line
			(start 0.7874 -0.4064)
			(end 0.7874 0.4064)
			(stroke
				(width 0.1524)
				(type default)
			)
			(layer "F.SilkS")
		)
		(fp_line
			(start -0.7874 0.4064)
			(end -0.7874 -0.4064)
			(stroke
				(width 0.1524)
				(type default)
			)
			(layer "F.SilkS")
		)
		(fp_line
			(start -0.7874 -0.4064)
			(end 0.7874 -0.4064)
			(stroke
				(width 0.1524)
				(type default)
			)
			(layer "F.SilkS")
		)
		(fp_line
			(start 0.67945 0.3048)
			(end 0.120396 0.3048)
			(stroke
				(width 0.1)
				(type default)
			)
			(layer "F.Fab")
		)
		(fp_line
			(start 0.67945 -0.3048)
			(end 0.67945 0.3048)
			(stroke
				(width 0.1)
				(type default)
			)
			(layer "F.Fab")
		)
		(fp_line
			(start 0.12065 -0.2794)
			(end 0.12065 -0.3048)
			(stroke
				(width 0.1)
				(type default)
			)
			(layer "F.Fab")
		)
		(fp_line
			(start 0.12065 -0.3048)
			(end 0.67945 -0.3048)
			(stroke
				(width 0.1)
				(type default)
			)
			(layer "F.Fab")
		)
		(fp_line
			(start 0.120396 0.3048)
			(end 0.120396 0.2794)
			(stroke
				(width 0.1)
				(type default)
			)
			(layer "F.Fab")
		)
		(fp_line
			(start 0.120396 0.2794)
			(end -0.12065 0.2794)
			(stroke
				(width 0.1)
				(type default)
			)
			(layer "F.Fab")
		)
		(fp_line
			(start -0.12065 0.3048)
			(end -0.67945 0.3048)
			(stroke
				(width 0.1)
				(type default)
			)
			(layer "F.Fab")
		)
		(fp_line
			(start -0.12065 0.2794)
			(end -0.12065 0.3048)
			(stroke
				(width 0.1)
				(type default)
			)
			(layer "F.Fab")
		)
		(fp_line
			(start -0.12065 -0.2794)
			(end 0.12065 -0.2794)
			(stroke
				(width 0.1)
				(type default)
			)
			(layer "F.Fab")
		)
		(fp_line
			(start -0.12065 -0.305054)
			(end -0.12065 -0.2794)
			(stroke
				(width 0.1)
				(type default)
			)
			(layer "F.Fab")
		)
		(fp_line
			(start -0.67945 0.3048)
			(end -0.67945 -0.305054)
			(stroke
				(width 0.1)
				(type default)
			)
			(layer "F.Fab")
		)
		(fp_line
			(start -0.67945 -0.305054)
			(end -0.12065 -0.305054)
			(stroke
				(width 0.1)
				(type default)
			)
			(layer "F.Fab")
		)
		(pad "1" smd circle
			(at -0.40005 0 180)
			(size 0 0)
			(layers "F.Cu" "F.Mask" "F.Paste")
			(net "P3V3_AUX")
		)
		(pad "2" smd circle
			(at 0.40005 0 180)
			(size 0 0)
			(layers "F.Cu" "F.Mask" "F.Paste")
			(net "HP_LVC3_E1S_0_HSC_PWRGD")
		)
	)
	(footprint ""
		(layer "F.Cu")
		(at 86.94039 -53.875686 90)
		(property "Reference" "PC2149"
			(at 0 0 90)
			(layer "F.SilkS")
			(hide yes)
			(effects
				(font
					(size 1.27 1.27)
				)
			)
		)
		(property "Value" ""
			(at 0 0 90)
			(layer "F.Fab")
			(effects
				(font
					(size 1.27 1.27)
				)
			)
		)
		(duplicate_pad_numbers_are_jumpers no)
		(fp_line
			(start 0.7874 -0.4064)
			(end 0.7874 0.4064)
			(stroke
				(width 0.1524)
				(type default)
			)
			(layer "F.SilkS")
		)
		(fp_line
			(start -0.7874 -0.4064)
			(end 0.7874 -0.4064)
			(stroke
				(width 0.1524)
				(type default)
			)
			(layer "F.SilkS")
		)
		(fp_line
			(start 0.7874 0.4064)
			(end -0.7874 0.4064)
			(stroke
				(width 0.1524)
				(type default)
			)
			(layer "F.SilkS")
		)
		(fp_line
			(start -0.7874 0.4064)
			(end -0.7874 -0.4064)
			(stroke
				(width 0.1524)
				(type default)
			)
			(layer "F.SilkS")
		)
		(fp_line
			(start -0.12065 -0.305054)
			(end -0.12065 -0.2794)
			(stroke
				(width 0.1)
				(type default)
			)
			(layer "F.Fab")
		)
		(fp_line
			(start -0.67945 -0.305054)
			(end -0.12065 -0.305054)
			(stroke
				(width 0.1)
				(type default)
			)
			(layer "F.Fab")
		)
		(fp_line
			(start 0.67945 -0.3048)
			(end 0.67945 0.3048)
			(stroke
				(width 0.1)
				(type default)
			)
			(layer "F.Fab")
		)
		(fp_line
			(start 0.12065 -0.3048)
			(end 0.67945 -0.3048)
			(stroke
				(width 0.1)
				(type default)
			)
			(layer "F.Fab")
		)
		(fp_line
			(start 0.12065 -0.2794)
			(end 0.12065 -0.3048)
			(stroke
				(width 0.1)
				(type default)
			)
			(layer "F.Fab")
		)
		(fp_line
			(start -0.12065 -0.2794)
			(end 0.12065 -0.2794)
			(stroke
				(width 0.1)
				(type default)
			)
			(layer "F.Fab")
		)
		(fp_line
			(start 0.120396 0.2794)
			(end -0.12065 0.2794)
			(stroke
				(width 0.1)
				(type default)
			)
			(layer "F.Fab")
		)
		(fp_line
			(start -0.12065 0.2794)
			(end -0.12065 0.3048)
			(stroke
				(width 0.1)
				(type default)
			)
			(layer "F.Fab")
		)
		(fp_line
			(start 0.67945 0.3048)
			(end 0.120396 0.3048)
			(stroke
				(width 0.1)
				(type default)
			)
			(layer "F.Fab")
		)
		(fp_line
			(start 0.120396 0.3048)
			(end 0.120396 0.2794)
			(stroke
				(width 0.1)
				(type default)
			)
			(layer "F.Fab")
		)
		(fp_line
			(start -0.12065 0.3048)
			(end -0.67945 0.3048)
			(stroke
				(width 0.1)
				(type default)
			)
			(layer "F.Fab")
		)
		(fp_line
			(start -0.67945 0.3048)
			(end -0.67945 -0.305054)
			(stroke
				(width 0.1)
				(type default)
			)
			(layer "F.Fab")
		)
		(pad "1" smd circle
			(at -0.40005 0 90)
			(size 0 0)
			(layers "F.Cu" "F.Mask" "F.Paste")
			(net "P3V3_OCP_V3_2_R")
		)
		(pad "2" smd circle
			(at 0.40005 0 90)
			(size 0 0)
			(layers "F.Cu" "F.Mask" "F.Paste")
			(net "P3V3_OCP_GATE_2")
		)
	)
)
